#ISCELL
  mstr_misc dns *
  *
#ISCELL
  pure_quanta quanta_title_block_c *
  *
#ISCELL
  logical_power universal_gnd *
  page48_i24
#ISCELL
  logical_power vccaux15 *
  page48_i25
#ISCELL
  standard offpage *
  page48_i31
#CELL
  pure_quanta q_res *
  page48_i33
#ISCELL
  standard offpage *
  page48_i37
#ISCELL
  logical_power universal_gnd *
  page48_i38
#CELL
  pure_quanta q_res *
  page48_i39
#CELL
  pure_quanta q_res *
  page48_i40
#ISCELL
  logical_power vccaux15 *
  page48_i41
#CELL
  pure_quanta q_res *
  page48_i42
#ISCELL
  standard offpage *
  page48_i45
#ISCELL
  standard offpage *
  page48_i46
#ISCELL
  logical_power vccaux15 *
  page48_i47
#CELL
  pure_quanta q_res *
  page48_i48
#ISCELL
  logical_power vccaux15 *
  page48_i49
#CELL
  pure_quanta q_res *
  page48_i50
#CELL
  pure_quanta q_res *
  page48_i51
#CELL
  pure_quanta q_res *
  page48_i52
#CELL
  pure_quanta q_res *
  page48_i53
#ISCELL
  logical_power universal_gnd *
  page48_i54
#ISCELL
  logical_power universal_gnd *
  page48_i55
#CELL
  pure_quanta q_res *
  page48_i56
